# TIMECARD (Time Appliance Project (Time Card)) — schematic netlist excerpt (pin names and nets, part order shuffled) for the footprints in the layout excerpt that follows; sources: Cadence DE-HDL packaged netlist, KiCad conversion of R4006-B0001-02_R01.brd

DS16  LED_4P_V14  pkg SMC_DS4_098X039  page 26
  \1\  = UNNAMED_14_LED4PV14_I267_1
  \2\  = XP3R3V_FPGA
  \3\  = UNNAMED_14_LED4PV14_I267_3
  \4\  = UNNAMED_14_LED4PV14_I267_4

(kicad_pcb
	(version 20260206)
	(generator "pcbnew")
	(generator_version "10.0")
	(general
		(thickness 1.6)
		(legacy_teardrops no)
	)
	(paper "A4")
	(title_block
		(title "timecard-production-celestica-r4006 — R4006-B0001-02_R01.brd")
		(comment 1 "Time Appliance Project (Time Card) / footprints 353-353 of 1113")
	)
	(layers
		(0 "F.Cu" signal "TOP")
		(4 "In1.Cu" signal "L02_GND1")
		(6 "In2.Cu" signal "L03_SIG1")
		(8 "In3.Cu" signal "L04_GND2")
		(10 "In4.Cu" signal "L05_VCC1")
		(12 "In5.Cu" signal "L06_VCC2")
		(14 "In6.Cu" signal "L07_GND3")
		(16 "In7.Cu" signal "L08_SIG2")
		(18 "In8.Cu" signal "L09_GND4")
		(2 "B.Cu" signal "BOTTOM")
		(9 "F.Adhes" user "F.Adhesive")
		(11 "B.Adhes" user "B.Adhesive")
		(13 "F.Paste" user "Package Geometry/Pastemask Top")
		(15 "B.Paste" user "Package Geometry/Pastemask Bottom")
		(5 "F.SilkS" user "Ref Des/Silkscreen Top")
		(7 "B.SilkS" user "Ref Des/Silkscreen Bottom")
		(1 "F.Mask" user "Board Geometry/Soldermask Top")
		(3 "B.Mask" user "Board Geometry/Soldermask Bottom")
		(17 "Dwgs.User" user "User.Drawings")
		(19 "Cmts.User" user "User.Comments")
		(21 "Eco1.User" user "User.Eco1")
		(23 "Eco2.User" user "User.Eco2")
		(25 "Edge.Cuts" user "Board Geometry/Outline")
		(27 "Margin" user)
		(31 "F.CrtYd" user "Package Geometry/Place Bound Top")
		(29 "B.CrtYd" user "Package Geometry/Place Bound Bottom")
		(35 "F.Fab" user "Ref Des/Assembly Top")
		(33 "B.Fab" user "Ref Des/Assembly Bottom")
	)
	(footprint ""
		(layer "F.Cu")
		(at 1.500124 -68.09994 90)
		(property "Reference" "DS16"
			(at 4.16306 1.587246 90)
			(unlocked yes)
			(layer "F.SilkS")
			(effects
				(font
					(size 0.7874 0.5842)
					(thickness 0.1524)
				)
			)
		)
		(property "Value" ""
			(at 0 0 90)
			(layer "F.Fab")
			(effects
				(font
					(size 1.27 1.27)
				)
			)
		)
		(property "User Part Number" "PARTNUM*"
			(at 0.015494 4.486402 90)
			(unlocked yes)
			(layer "Cmts.User")
			(hide yes)
			(effects
				(font
					(size 0.7874 0.5842)
					(thickness 0.1524)
				)
			)
		)
		(property "Device Type" "LED_4P_V14-G170-10189-01"
			(at 0.015494 3.292602 90)
			(unlocked yes)
			(layer "F.Fab")
			(hide yes)
			(effects
				(font
					(size 0.7874 0.5842)
					(thickness 0.1524)
				)
			)
		)
		(duplicate_pad_numbers_are_jumpers no)
		(fp_line
			(start 1.378966 -0.829056)
			(end -1.378966 -0.829056)
			(stroke
				(width 0.1)
				(type default)
			)
			(layer "F.SilkS")
		)
		(fp_line
			(start -1.378966 -0.829056)
			(end -1.378966 -0.452628)
			(stroke
				(width 0.1)
				(type default)
			)
			(layer "F.SilkS")
		)
		(fp_line
			(start 1.998218 -0.452628)
			(end 1.378966 -0.452628)
			(stroke
				(width 0.1)
				(type default)
			)
			(layer "F.SilkS")
		)
		(fp_line
			(start 1.378966 -0.452628)
			(end 1.378966 -0.829056)
			(stroke
				(width 0.1)
				(type default)
			)
			(layer "F.SilkS")
		)
		(fp_line
			(start -1.378966 -0.452628)
			(end -1.998218 -0.452628)
			(stroke
				(width 0.1)
				(type default)
			)
			(layer "F.SilkS")
		)
		(fp_line
			(start -1.998218 -0.452628)
			(end -1.998218 1.103884)
			(stroke
				(width 0.1)
				(type default)
			)
			(layer "F.SilkS")
		)
		(fp_line
			(start 1.998218 1.103884)
			(end 1.998218 -0.452628)
			(stroke
				(width 0.1)
				(type default)
			)
			(layer "F.SilkS")
		)
		(fp_line
			(start -1.998218 1.103884)
			(end 1.998218 1.103884)
			(stroke
				(width 0.1)
				(type default)
			)
			(layer "F.SilkS")
		)
		(fp_poly
			(pts
				(xy 0.918464 -1.698498) (xy 1.223264 -1.46939) (xy 0.994664 -1.46939) (xy 0.994664 -1.24079) (xy 0.842264 -1.24079)
				(xy 0.842264 -1.46939) (xy 0.613664 -1.46939)
			)
			(stroke
				(width 0)
				(type default)
			)
			(fill yes)
			(layer "F.SilkS")
		)
		(fp_poly
			(pts
				(xy -0.73406 -1.677416) (xy -0.42926 -1.448308) (xy -0.65786 -1.448308) (xy -0.65786 -1.219708)
				(xy -0.81026 -1.219708) (xy -0.81026 -1.448308) (xy -1.03886 -1.448308)
			)
			(stroke
				(width 0)
				(type default)
			)
			(fill yes)
			(layer "F.SilkS")
		)
		(fp_poly
			(pts
				(xy -2.252218 1.357884) (xy -2.252218 -0.706628) (xy -1.632966 -0.706628) (xy -1.632966 -1.083056)
				(xy 1.632966 -1.083056) (xy 1.632966 -0.706628) (xy 2.252218 -0.706628) (xy 2.252218 1.357884)
			)
			(stroke
				(width 0)
				(type default)
			)
			(fill no)
			(layer "F.CrtYd")
		)
		(fp_line
			(start 1.124966 -0.575056)
			(end -1.124966 -0.575056)
			(stroke
				(width 0.1)
				(type default)
			)
			(layer "F.Fab")
		)
		(fp_line
			(start -1.124966 -0.575056)
			(end -1.124966 -0.075184)
			(stroke
				(width 0.1)
				(type default)
			)
			(layer "F.Fab")
		)
		(fp_line
			(start 1.325118 -0.075184)
			(end 1.124966 -0.075184)
			(stroke
				(width 0.1)
				(type default)
			)
			(layer "F.Fab")
		)
		(fp_line
			(start 1.124966 -0.075184)
			(end 1.124966 -0.575056)
			(stroke
				(width 0.1)
				(type default)
			)
			(layer "F.Fab")
		)
		(fp_line
			(start -1.124966 -0.075184)
			(end -1.325118 -0.075184)
			(stroke
				(width 0.1)
				(type default)
			)
			(layer "F.Fab")
		)
		(fp_line
			(start -1.325118 -0.075184)
			(end -1.325118 0.574802)
			(stroke
				(width 0.1)
				(type default)
			)
			(layer "F.Fab")
		)
		(fp_line
			(start 1.325118 0.574802)
			(end 1.325118 -0.075184)
			(stroke
				(width 0.1)
				(type default)
			)
			(layer "F.Fab")
		)
		(fp_line
			(start -1.325118 0.574802)
			(end 1.325118 0.574802)
			(stroke
				(width 0.1)
				(type default)
			)
			(layer "F.Fab")
		)
		(fp_poly
			(pts
				(xy 0.918464 -1.698498) (xy 1.223264 -1.46939) (xy 0.994664 -1.46939) (xy 0.994664 -1.24079) (xy 0.842264 -1.24079)
				(xy 0.842264 -1.46939) (xy 0.613664 -1.46939)
			)
			(stroke
				(width 0)
				(type default)
			)
			(fill yes)
			(layer "F.Fab")
		)
		(fp_poly
			(pts
				(xy -0.73406 -1.677416) (xy -0.42926 -1.448308) (xy -0.65786 -1.448308) (xy -0.65786 -1.219708)
				(xy -0.81026 -1.219708) (xy -0.81026 -1.448308) (xy -1.03886 -1.448308)
			)
			(stroke
				(width 0)
				(type default)
			)
			(fill yes)
			(layer "F.Fab")
		)
		(fp_text user "1"
			(at -2.37617 0.376936 90)
			(unlocked yes)
			(layer "F.SilkS")
			(effects
				(font
					(size 0.7874 0.5842)
					(thickness 0.1524)
				)
			)
		)
		(fp_text user "3"
			(at 0.69469 2.055876 0)
			(unlocked yes)
			(layer "F.SilkS")
			(effects
				(font
					(size 0.7874 0.5842)
					(thickness 0.1524)
				)
			)
		)
		(fp_text user "2"
			(at -0.44831 2.182876 0)
			(unlocked yes)
			(layer "F.SilkS")
			(effects
				(font
					(size 0.7874 0.5842)
					(thickness 0.1524)
				)
			)
		)
		(fp_text user "4"
			(at 1.77038 1.166876 0)
			(unlocked yes)
			(layer "F.Fab")
			(effects
				(font
					(size 0.7874 0.5842)
					(thickness 0.1524)
				)
			)
		)
		(fp_text user "3"
			(at 0.75438 1.166876 0)
			(unlocked yes)
			(layer "F.Fab")
			(effects
				(font
					(size 0.7874 0.5842)
					(thickness 0.1524)
				)
			)
		)
		(fp_text user "2"
			(at -0.38862 1.166876 0)
			(unlocked yes)
			(layer "F.Fab")
			(effects
				(font
					(size 0.7874 0.5842)
					(thickness 0.1524)
				)
			)
		)
		(fp_text user "1"
			(at -1.46431 1.293876 0)
			(unlocked yes)
			(layer "F.Fab")
			(effects
				(font
					(size 0.7874 0.5842)
					(thickness 0.1524)
				)
			)
		)
		(pad "1" smd rect
			(at -1.325118 0.245872 90)
			(size 0.8382 0.889)
			(layers "F.Cu" "F.Mask" "F.Paste")
			(net "UNNAMED_14_LED4PV14_I267_1")
		)
		(pad "2" smd rect
			(at -0.424942 0.595884 90)
			(size 0.4572 0.508)
			(layers "F.Cu" "F.Mask" "F.Paste")
			(net "XP3R3V_FPGA")
		)
		(pad "3" smd rect
			(at 0.424942 0.595884 90)
			(size 0.4572 0.508)
			(layers "F.Cu" "F.Mask" "F.Paste")
			(net "UNNAMED_14_LED4PV14_I267_3")
		)
		(pad "4" smd rect
			(at 1.325118 0.245872 90)
			(size 0.8382 0.889)
			(layers "F.Cu" "F.Mask" "F.Paste")
			(net "UNNAMED_14_LED4PV14_I267_4")
		)
	)
)
